(kicad_pcb
	(version 20241229)
	(generator "pcbnew")
	(generator_version "9.0")
	(general
		(thickness 1.711)
		(legacy_teardrops no)
	)
	(paper "A4")
	(title_block
		(title "Antmicro Baseboard for Jetson AGX Thor")
		(date "2026-02-18")
		(rev "1.1.0")
		(company "Antmicro Ltd")
		(comment 1 "www.antmicro.com")
		(comment 9 "footprints 541-544 of 1170")
	)
	(layers
		(0 "F.Cu" signal)
		(4 "In1.Cu" signal)
		(6 "In2.Cu" signal)
		(8 "In3.Cu" signal)
		(10 "In4.Cu" jumper)
		(12 "In5.Cu" signal)
		(14 "In6.Cu" signal)
		(16 "In7.Cu" signal)
		(18 "In8.Cu" signal)
		(2 "B.Cu" signal)
		(9 "F.Adhes" user "F.Adhesive")
		(11 "B.Adhes" user "B.Adhesive")
		(13 "F.Paste" user)
		(15 "B.Paste" user)
		(5 "F.SilkS" user "F.Silkscreen")
		(7 "B.SilkS" user "B.Silkscreen")
		(1 "F.Mask" user)
		(3 "B.Mask" user)
		(17 "Dwgs.User" user "User.Drawings")
		(19 "Cmts.User" user "User.Comments")
		(21 "Eco1.User" user "User.Eco1")
		(23 "Eco2.User" user "User.Eco2")
		(25 "Edge.Cuts" user)
		(27 "Margin" user)
		(31 "F.CrtYd" user "F.Courtyard")
		(29 "B.CrtYd" user "B.Courtyard")
		(35 "F.Fab" user)
		(33 "B.Fab" user)
	)
	(footprint "antmicro-footprints:R_0402_1005Metric"
		(layer "F.Cu")
		(at 106.85 56.68)
		(descr "Resistor SMD 0402")
		(tags "resistor SMD 0402")
		(property "Reference" "R367"
			(at -2.73 6.16 0)
			(layer "F.SilkS")
			(effects
				(font
					(size 0.7 0.7)
					(thickness 0.15)
				)
				(justify left bottom)
			)
		)
		(property "Value" "R_27R_0402"
			(at -1.011843 1.772046 0)
			(layer "F.Fab")
			(effects
				(font
					(size 0.7 0.7)
					(thickness 0.15)
				)
				(justify left bottom)
			)
		)
		(property "Datasheet" "https://www.bourns.com/docs/product-datasheets/cr.pdf"
			(at 0 0 0)
			(layer "F.Fab")
			(hide yes)
			(effects
				(font
					(size 1.27 1.27)
					(thickness 0.15)
				)
			)
		)
		(property "Description" "SMD Chip Resistor, 27 ohm, ± 1%, 63 mW, 0402 [1005 Metric], Thick Film, General Purpose"
			(at 0 0 0)
			(layer "F.Fab")
			(hide yes)
			(effects
				(font
					(size 1.27 1.27)
					(thickness 0.15)
				)
			)
		)
		(property "Manufacturer" "Bourns"
			(at 0 0 0)
			(unlocked yes)
			(layer "F.Fab")
			(hide yes)
			(effects
				(font
					(size 1 1)
					(thickness 0.15)
				)
			)
		)
		(property "MPN" "CR0402-FX-27R0GLF"
			(at 0 0 0)
			(unlocked yes)
			(layer "F.Fab")
			(hide yes)
			(effects
				(font
					(size 1 1)
					(thickness 0.15)
				)
			)
		)
		(property "Val" "27R"
			(at 0 0 0)
			(unlocked yes)
			(layer "F.Fab")
			(hide yes)
			(effects
				(font
					(size 1 1)
					(thickness 0.15)
				)
			)
		)
		(property "License" "Apache-2.0"
			(at 0 0 0)
			(unlocked yes)
			(layer "F.Fab")
			(hide yes)
			(effects
				(font
					(size 1 1)
					(thickness 0.15)
				)
			)
		)
		(property "Author" "Antmicro"
			(at 0 0 0)
			(unlocked yes)
			(layer "F.Fab")
			(hide yes)
			(effects
				(font
					(size 1 1)
					(thickness 0.15)
				)
			)
		)
		(property "Tolerance" "1%"
			(at 0 0 0)
			(unlocked yes)
			(layer "F.Fab")
			(hide yes)
			(effects
				(font
					(size 1 1)
					(thickness 0.15)
				)
			)
		)
		(sheetname "/DCDC/")
		(sheetfile "dcdc.kicad_sch")
		(attr smd)
		(fp_poly
			(pts
				(xy -0.925 -0.47) (xy -0.925 0.47) (xy 0.925 0.47) (xy 0.925 -0.47)
			)
			(stroke
				(width 0.05)
				(type default)
			)
			(fill no)
			(layer "F.CrtYd")
		)
		(fp_poly
			(pts
				(xy -0.5 -0.25) (xy -0.5 0.25) (xy 0.5 0.25) (xy 0.5 -0.25)
			)
			(stroke
				(width 0.15)
				(type solid)
			)
			(fill no)
			(layer "F.Fab")
		)
		(fp_text user "License: Apache-2.0"
			(at -0.949999 5.169 0)
			(layer "F.Fab")
			(effects
				(font
					(size 0.7 0.7)
					(thickness 0.15)
				)
				(justify left bottom)
			)
		)
		(fp_text user "${REFERENCE}"
			(at -0.95 3.168 0)
			(layer "F.Fab")
			(effects
				(font
					(size 0.7 0.7)
					(thickness 0.15)
				)
				(justify left bottom)
			)
		)
		(fp_text user "Author: Antmicro"
			(at -0.95 4.169 0)
			(layer "F.Fab")
			(effects
				(font
					(size 0.7 0.7)
					(thickness 0.15)
				)
				(justify left bottom)
			)
		)
		(pad "1" smd roundrect
			(at -0.48 0)
			(size 0.59 0.64)
			(layers "F.Cu" "F.Mask" "F.Paste")
			(roundrect_rratio 0.25)
			(net 1279 "Net-(U76-IN-)")
			(pintype "passive")
		)
		(pad "2" smd roundrect
			(at 0.48 0)
			(size 0.59 0.64)
			(layers "F.Cu" "F.Mask" "F.Paste")
			(roundrect_rratio 0.25)
			(net 491 "+5V_AON")
			(pintype "passive")
		)
	)
	(footprint "antmicro-footprints:R_0402_1005Metric"
		(layer "F.Cu")
		(at 61.6 64.2)
		(descr "Resistor SMD 0402")
		(tags "resistor SMD 0402")
		(property "Reference" "R167"
			(at -1.4 3.6 0)
			(layer "F.SilkS")
			(effects
				(font
					(size 0.7 0.7)
					(thickness 0.15)
				)
				(justify left bottom)
			)
		)
		(property "Value" "R_10k_0402"
			(at -1.011843 1.772046 0)
			(layer "F.Fab")
			(effects
				(font
					(size 0.7 0.7)
					(thickness 0.15)
				)
				(justify left bottom)
			)
		)
		(property "Datasheet" "https://www.bourns.com/docs/product-datasheets/cr.pdf"
			(at 0 0 0)
			(layer "F.Fab")
			(hide yes)
			(effects
				(font
					(size 1.27 1.27)
					(thickness 0.15)
				)
			)
		)
		(property "Description" "SMD Chip Resistor, 10 kohm, ± 1%, 62.5 mW, 0402 [1005 Metric], Thick Film, General Purpose"
			(at 0 0 0)
			(layer "F.Fab")
			(hide yes)
			(effects
				(font
					(size 1.27 1.27)
					(thickness 0.15)
				)
			)
		)
		(property "Manufacturer" "Bourns"
			(at 0 0 0)
			(unlocked yes)
			(layer "F.Fab")
			(hide yes)
			(effects
				(font
					(size 1 1)
					(thickness 0.15)
				)
			)
		)
		(property "MPN" "CR0402-FX-1002GLF"
			(at 0 0 0)
			(unlocked yes)
			(layer "F.Fab")
			(hide yes)
			(effects
				(font
					(size 1 1)
					(thickness 0.15)
				)
			)
		)
		(property "Val" "10k"
			(at 0 0 0)
			(unlocked yes)
			(layer "F.Fab")
			(hide yes)
			(effects
				(font
					(size 1 1)
					(thickness 0.15)
				)
			)
		)
		(property "License" "Apache-2.0"
			(at 0 0 0)
			(unlocked yes)
			(layer "F.Fab")
			(hide yes)
			(effects
				(font
					(size 1 1)
					(thickness 0.15)
				)
			)
		)
		(property "Author" "Antmicro"
			(at 0 0 0)
			(unlocked yes)
			(layer "F.Fab")
			(hide yes)
			(effects
				(font
					(size 1 1)
					(thickness 0.15)
				)
			)
		)
		(property "Tolerance" "1%"
			(at 0 0 0)
			(unlocked yes)
			(layer "F.Fab")
			(hide yes)
			(effects
				(font
					(size 1 1)
					(thickness 0.15)
				)
			)
		)
		(sheetname "/CSI/")
		(sheetfile "csi.kicad_sch")
		(attr smd)
		(fp_poly
			(pts
				(xy -0.925 -0.47) (xy -0.925 0.47) (xy 0.925 0.47) (xy 0.925 -0.47)
			)
			(stroke
				(width 0.05)
				(type default)
			)
			(fill no)
			(layer "F.CrtYd")
		)
		(fp_poly
			(pts
				(xy -0.5 -0.25) (xy -0.5 0.25) (xy 0.5 0.25) (xy 0.5 -0.25)
			)
			(stroke
				(width 0.15)
				(type solid)
			)
			(fill no)
			(layer "F.Fab")
		)
		(fp_text user "License: Apache-2.0"
			(at -0.949999 5.169 0)
			(layer "F.Fab")
			(effects
				(font
					(size 0.7 0.7)
					(thickness 0.15)
				)
				(justify left bottom)
			)
		)
		(fp_text user "Author: Antmicro"
			(at -0.95 4.169 0)
			(layer "F.Fab")
			(effects
				(font
					(size 0.7 0.7)
					(thickness 0.15)
				)
				(justify left bottom)
			)
		)
		(fp_text user "${REFERENCE}"
			(at -0.95 3.168 0)
			(layer "F.Fab")
			(effects
				(font
					(size 0.7 0.7)
					(thickness 0.15)
				)
				(justify left bottom)
			)
		)
		(pad "1" smd roundrect
			(at -0.48 0)
			(size 0.59 0.64)
			(layers "F.Cu" "F.Mask" "F.Paste")
			(roundrect_rratio 0.25)
			(net 11 "+1V8")
			(pintype "passive")
		)
		(pad "2" smd roundrect
			(at 0.48 0)
			(size 0.59 0.64)
			(layers "F.Cu" "F.Mask" "F.Paste")
			(roundrect_rratio 0.25)
			(net 989 "/CSI/I2C_MUX_RESET")
			(pintype "passive")
		)
	)
	(footprint "antmicro-footprints:C_0402_1005Metric"
		(layer "F.Cu")
		(at 200.7 133.7 90)
		(descr "Capacitor SMD 0402")
		(tags "capacitor SMD 0402")
		(property "Reference" "C97"
			(at -1.105 -1.8 90)
			(layer "F.SilkS")
			(effects
				(font
					(size 0.7 0.7)
					(thickness 0.15)
				)
				(justify left bottom)
			)
		)
		(property "Value" "C_100n_0402"
			(at -1.022927 2.155213 90)
			(layer "F.Fab")
			(effects
				(font
					(size 0.7 0.7)
					(thickness 0.15)
				)
				(justify left bottom)
			)
		)
		(property "Datasheet" "https://www.murata.com/products/productdetail?partno=GRM155R61H104KE14%23"
			(at 0 0 90)
			(layer "F.Fab")
			(hide yes)
			(effects
				(font
					(size 1.27 1.27)
					(thickness 0.15)
				)
			)
		)
		(property "Description" "SMD Multilayer Ceramic Capacitor, 0.1 µF, 50 V, 0402 [1005 Metric], ± 10%, X5R, GRM Series"
			(at 0 0 90)
			(layer "F.Fab")
			(hide yes)
			(effects
				(font
					(size 1.27 1.27)
					(thickness 0.15)
				)
			)
		)
		(property "MPN" "GRM155R61H104KE14D"
			(at 0 0 90)
			(unlocked yes)
			(layer "F.Fab")
			(hide yes)
			(effects
				(font
					(size 1 1)
					(thickness 0.15)
				)
			)
		)
		(property "Val" "100n"
			(at 0 0 90)
			(unlocked yes)
			(layer "F.Fab")
			(hide yes)
			(effects
				(font
					(size 1 1)
					(thickness 0.15)
				)
			)
		)
		(property "Voltage" "50V"
			(at 0 0 90)
			(unlocked yes)
			(layer "F.Fab")
			(hide yes)
			(effects
				(font
					(size 1 1)
					(thickness 0.15)
				)
			)
		)
		(property "Dielectric" "X5R"
			(at 0 0 90)
			(unlocked yes)
			(layer "F.Fab")
			(hide yes)
			(effects
				(font
					(size 1 1)
					(thickness 0.15)
				)
			)
		)
		(property "Manufacturer" "Murata"
			(at 0 0 90)
			(unlocked yes)
			(layer "F.Fab")
			(hide yes)
			(effects
				(font
					(size 1 1)
					(thickness 0.15)
				)
			)
		)
		(property "License" "Apache-2.0"
			(at 0 0 90)
			(unlocked yes)
			(layer "F.Fab")
			(hide yes)
			(effects
				(font
					(size 1 1)
					(thickness 0.15)
				)
			)
		)
		(property "Author" "Antmicro"
			(at 0 0 90)
			(unlocked yes)
			(layer "F.Fab")
			(hide yes)
			(effects
				(font
					(size 1 1)
					(thickness 0.15)
				)
			)
		)
		(sheetname "/USB Hub/")
		(sheetfile "usb_hub.kicad_sch")
		(attr smd)
		(fp_poly
			(pts
				(xy -0.925 -0.47) (xy 0.925 -0.47) (xy 0.925 0.47) (xy -0.925 0.47)
			)
			(stroke
				(width 0.05)
				(type default)
			)
			(fill no)
			(layer "F.CrtYd")
		)
		(fp_line
			(start 0.504 -0.25)
			(end 0.504 0.248)
			(stroke
				(width 0.15)
				(type solid)
			)
			(layer "F.Fab")
		)
		(fp_line
			(start -0.494 -0.25)
			(end 0.504 -0.25)
			(stroke
				(width 0.15)
				(type solid)
			)
			(layer "F.Fab")
		)
		(fp_line
			(start 0.504 0.248)
			(end -0.494 0.248)
			(stroke
				(width 0.15)
				(type solid)
			)
			(layer "F.Fab")
		)
		(fp_line
			(start -0.494 0.248)
			(end -0.494 -0.25)
			(stroke
				(width 0.15)
				(type solid)
			)
			(layer "F.Fab")
		)
		(fp_text user "${REFERENCE}"
			(at -0.939 4.599 90)
			(layer "F.Fab")
			(effects
				(font
					(size 0.7 0.7)
					(thickness 0.15)
				)
				(justify left bottom)
			)
		)
		(fp_text user "License: Apache-2.0"
			(at -0.939 5.799 90)
			(layer "F.Fab")
			(effects
				(font
					(size 0.7 0.7)
					(thickness 0.15)
				)
				(justify left bottom)
			)
		)
		(fp_text user "Author: Antmicro"
			(at -0.939 3.399 90)
			(layer "F.Fab")
			(effects
				(font
					(size 0.7 0.7)
					(thickness 0.15)
				)
				(justify left bottom)
			)
		)
		(pad "1" smd roundrect
			(at -0.48 0 90)
			(size 0.59 0.64)
			(layers "F.Cu" "F.Mask" "F.Paste")
			(roundrect_rratio 0.25)
			(net 1 "GND")
			(pintype "passive")
		)
		(pad "2" smd roundrect
			(at 0.48 0 90)
			(size 0.59 0.64)
			(layers "F.Cu" "F.Mask" "F.Paste")
			(roundrect_rratio 0.25)
			(net 282 "+1V15")
			(pintype "passive")
		)
	)
	(footprint "antmicro-footprints:R_0603_1608Metric"
		(layer "F.Cu")
		(at 193.89 124.08)
		(descr "Resistor SMD 0603")
		(tags "resistor SMD 0603")
		(property "Reference" "R7"
			(at -2.59 0.72 0)
			(layer "F.SilkS")
			(effects
				(font
					(size 0.7 0.7)
					(thickness 0.15)
				)
				(justify left bottom)
			)
		)
		(property "Value" "R_0R_22.4A_0603"
			(at 0 1.6 0)
			(layer "F.Fab")
			(effects
				(font
					(size 0.7 0.7)
					(thickness 0.15)
				)
				(justify left bottom)
			)
		)
		(property "Datasheet" "https://fscdn.rohm.com/en/products/databook/datasheet/passive/resistor/chip_resistor/pmr-jpw-e.pdf"
			(at 0 0 0)
			(layer "F.Fab")
			(hide yes)
			(effects
				(font
					(size 1.27 1.27)
					(thickness 0.15)
				)
			)
		)
		(property "Description" "SMD Chip Resistor"
			(at 0 0 0)
			(layer "F.Fab")
			(hide yes)
			(effects
				(font
					(size 1.27 1.27)
					(thickness 0.15)
				)
			)
		)
		(property "Manufacturer" "ROHM Semiconductor"
			(at 0 0 0)
			(unlocked yes)
			(layer "F.Fab")
			(hide yes)
			(effects
				(font
					(size 1 1)
					(thickness 0.15)
				)
			)
		)
		(property "MPN" "PMR03EZPJ000"
			(at 0 0 0)
			(unlocked yes)
			(layer "F.Fab")
			(hide yes)
			(effects
				(font
					(size 1 1)
					(thickness 0.15)
				)
			)
		)
		(property "Val" "0R"
			(at 0 0 0)
			(unlocked yes)
			(layer "F.Fab")
			(hide yes)
			(effects
				(font
					(size 1 1)
					(thickness 0.15)
				)
			)
		)
		(property "Author" "Antmicro"
			(at 0 0 0)
			(unlocked yes)
			(layer "F.Fab")
			(hide yes)
			(effects
				(font
					(size 1 1)
					(thickness 0.15)
				)
			)
		)
		(property "License" "Apache-2.0"
			(at 0 0 0)
			(unlocked yes)
			(layer "F.Fab")
			(hide yes)
			(effects
				(font
					(size 1 1)
					(thickness 0.15)
				)
			)
		)
		(property "Max. Curr." "22.4A"
			(at 0 0 0)
			(unlocked yes)
			(layer "F.Fab")
			(hide yes)
			(effects
				(font
					(size 1 1)
					(thickness 0.15)
				)
			)
		)
		(property "Tolerance" "template_tolerance"
			(at 0 0 0)
			(unlocked yes)
			(layer "F.Fab")
			(hide yes)
			(effects
				(font
					(size 1 1)
					(thickness 0.15)
				)
			)
		)
		(component_classes
			(class "DCDC_1V15")
		)
		(sheetname "/DCDC/")
		(sheetfile "dcdc.kicad_sch")
		(attr smd)
		(fp_line
			(start -0.15 -0.4)
			(end 0.15 -0.4)
			(stroke
				(width 0.15)
				(type solid)
			)
			(layer "F.SilkS")
		)
		(fp_line
			(start -0.15 0.4)
			(end 0.15 0.4)
			(stroke
				(width 0.15)
				(type solid)
			)
			(layer "F.SilkS")
		)
		(fp_rect
			(start -1.25 -0.65)
			(end 1.25 0.65)
			(stroke
				(width 0.05)
				(type solid)
			)
			(fill no)
			(layer "F.CrtYd")
		)
		(fp_rect
			(start -0.8 -0.4)
			(end 0.8 0.4)
			(stroke
				(width 0.15)
				(type solid)
			)
			(fill no)
			(layer "F.Fab")
		)
		(fp_text user "${REFERENCE}"
			(at -1.25 3.898 0)
			(layer "F.Fab")
			(effects
				(font
					(size 0.7 0.7)
					(thickness 0.15)
				)
				(justify left bottom)
			)
		)
		(fp_text user "Author: Antmicro"
			(at -1.25 4.9 0)
			(layer "F.Fab")
			(effects
				(font
					(size 0.7 0.7)
					(thickness 0.15)
				)
				(justify left bottom)
			)
		)
		(fp_text user "License: Apache-2.0"
			(at -1.25 5.9 0)
			(layer "F.Fab")
			(effects
				(font
					(size 0.7 0.7)
					(thickness 0.15)
				)
				(justify left bottom)
			)
		)
		(pad "1" smd roundrect
			(at -0.7 0)
			(size 0.8 1)
			(layers "F.Cu" "F.Mask" "F.Paste")
			(roundrect_rratio 0.2)
			(net 280 "/DCDC/1V15_OUT")
			(pintype "passive")
		)
		(pad "2" smd roundrect
			(at 0.7 0)
			(size 0.8 1)
			(layers "F.Cu" "F.Mask" "F.Paste")
			(roundrect_rratio 0.2)
			(net 282 "+1V15")
			(pintype "passive")
		)
	)
)
